(kicad_pcb
	(version 20260206)
	(generator "pcbnew")
	(generator_version "10.0")
	(general
		(thickness 1.6)
		(legacy_teardrops no)
	)
	(paper "A4")
	(title_block
		(title "04192023_DAF0TMB3IC0_F0TG_MB_C_brd_V02_OCP.brd")
		(comment 1 "Grand Teton / footprints 7346-7351 of 8354")
	)
	(layers
		(0 "F.Cu" signal "TOP")
		(4 "In1.Cu" signal "GND")
		(6 "In2.Cu" signal "IN1")
		(8 "In3.Cu" signal "GND1")
		(10 "In4.Cu" signal "IN2")
		(12 "In5.Cu" signal "GND2")
		(14 "In6.Cu" signal "IN3")
		(16 "In7.Cu" signal "GND3")
		(18 "In8.Cu" signal "VCC")
		(20 "In9.Cu" signal "VCC1")
		(22 "In10.Cu" signal "GND4")
		(24 "In11.Cu" signal "IN4")
		(26 "In12.Cu" signal "GND5")
		(28 "In13.Cu" signal "IN5")
		(30 "In14.Cu" signal "GND6")
		(32 "In15.Cu" signal "IN6")
		(34 "In16.Cu" signal "GND7")
		(2 "B.Cu" signal "BOTTOM")
		(9 "F.Adhes" user "F.Adhesive")
		(11 "B.Adhes" user "B.Adhesive")
		(13 "F.Paste" user "Package Geometry/Pastemask Top")
		(15 "B.Paste" user "Package Geometry/Pastemask Bottom")
		(5 "F.SilkS" user "Ref Des/Silkscreen Top")
		(7 "B.SilkS" user "Ref Des/Silkscreen Bottom")
		(1 "F.Mask" user "Board Geometry/Soldermask Top")
		(3 "B.Mask" user "Board Geometry/Soldermask Bottom")
		(17 "Dwgs.User" user "User.Drawings")
		(19 "Cmts.User" user "User.Comments")
		(21 "Eco1.User" user "User.Eco1")
		(23 "Eco2.User" user "User.Eco2")
		(25 "Edge.Cuts" user "Board Geometry/Outline")
		(27 "Margin" user)
		(31 "F.CrtYd" user "Package Geometry/Place Bound Top")
		(29 "B.CrtYd" user "Package Geometry/Place Bound Bottom")
		(35 "F.Fab" user "Ref Des/Assembly Top")
		(33 "B.Fab" user "Ref Des/Assembly Bottom")
	)
	(footprint ""
		(layer "B.Cu")
		(at 522.584426 -298.381674 -90)
		(property "Reference" "X11"
			(at 3.303524 3.168396 270)
			(unlocked yes)
			(layer "B.SilkS")
			(effects
				(font
					(size 0.7874 0.5842)
					(thickness 0.1524)
				)
				(justify left mirror)
			)
		)
		(property "Value" ""
			(at 0 0 90)
			(layer "B.Fab")
			(effects
				(font
					(size 1.27 1.27)
				)
				(justify mirror)
			)
		)
		(property "User Part Number" "N_A"
			(at -1.30175 1.27 180)
			(unlocked yes)
			(layer "Cmts.User")
			(hide yes)
			(effects
				(font
					(size 0.635 0.4064)
					(thickness 0.1524)
				)
				(justify mirror)
			)
		)
		(property "Device Type" "TP_TDR_4P_FTS_TH-TP_TDR_4P_DIP,EMPTY,TP15"
			(at -1.30175 1.27 180)
			(unlocked yes)
			(layer "B.Fab")
			(hide yes)
			(effects
				(font
					(size 0.635 0.4064)
					(thickness 0.1524)
				)
				(justify mirror)
			)
		)
		(duplicate_pad_numbers_are_jumpers no)
		(fp_line
			(start -2.54 3.81)
			(end -2.54 3.6703)
			(stroke
				(width 0.1524)
				(type default)
			)
			(layer "B.SilkS")
		)
		(fp_line
			(start 0 3.81)
			(end -2.54 3.81)
			(stroke
				(width 0.1524)
				(type default)
			)
			(layer "B.SilkS")
		)
		(fp_line
			(start 0 3.175)
			(end 0 3.81)
			(stroke
				(width 0.1524)
				(type default)
			)
			(layer "B.SilkS")
		)
		(fp_line
			(start -2.54 1.4097)
			(end -2.54 1.1303)
			(stroke
				(width 0.1524)
				(type default)
			)
			(layer "B.SilkS")
		)
		(fp_line
			(start 0 0.635)
			(end 0 1.905)
			(stroke
				(width 0.1524)
				(type default)
			)
			(layer "B.SilkS")
		)
		(fp_line
			(start -2.54 -1.1303)
			(end -2.54 -1.27)
			(stroke
				(width 0.1524)
				(type default)
			)
			(layer "B.SilkS")
		)
		(fp_line
			(start -2.54 -1.27)
			(end 0 -1.27)
			(stroke
				(width 0.1524)
				(type default)
			)
			(layer "B.SilkS")
		)
		(fp_line
			(start 0 -1.27)
			(end 0 -0.635)
			(stroke
				(width 0.1524)
				(type default)
			)
			(layer "B.SilkS")
		)
		(fp_poly
			(pts
				(xy 2.285746 -0.762) (xy 2.285746 0.762) (xy 0.761746 0)
			)
			(stroke
				(width 0)
				(type default)
			)
			(fill yes)
			(layer "B.SilkS")
		)
		(fp_line
			(start -2.54 3.81)
			(end -2.54 -1.27)
			(stroke
				(width 0.1)
				(type default)
			)
			(layer "B.Fab")
		)
		(fp_line
			(start 0 3.81)
			(end -2.54 3.81)
			(stroke
				(width 0.1)
				(type default)
			)
			(layer "B.Fab")
		)
		(fp_line
			(start -2.54 -1.27)
			(end 0 -1.27)
			(stroke
				(width 0.1)
				(type default)
			)
			(layer "B.Fab")
		)
		(fp_line
			(start 0 -1.27)
			(end 0 3.81)
			(stroke
				(width 0.1)
				(type default)
			)
			(layer "B.Fab")
		)
		(fp_poly
			(pts
				(xy 0.761746 0) (xy 2.285746 -0.762) (xy 2.285746 0.762)
			)
			(stroke
				(width 0)
				(type default)
			)
			(fill yes)
			(layer "B.Fab")
		)
		(pad "1" thru_hole circle
			(at 0 0 90)
			(size 1.0033 1.0033)
			(drill 0.249936)
			(layers "*.Cu" "*.Mask")
			(remove_unused_layers no)
			(net "TDR_DIFF_80_IN4_DN")
			(clearance 0.10795)
			(padstack
				(mode front_inner_back)
				(layer "Inner"
					(shape circle)
					(size 0.8001 0.8001)
					(clearance 0.1524)
				)
				(layer "B.Cu"
					(shape circle)
					(size 1.0033 1.0033)
					(thermal_gap 0.10795)
					(clearance 0.10795)
				)
			)
		)
		(pad "2" thru_hole circle
			(at -2.54 0 90)
			(size 1.9939 1.9939)
			(drill 0.249936)
			(layers "*.Cu" "*.Mask")
			(remove_unused_layers no)
			(net "T1_GND")
			(clearance 0.10795)
			(padstack
				(mode front_inner_back)
				(layer "Inner"
					(shape circle)
					(size 0.8001 0.8001)
					(clearance 0.1524)
				)
				(layer "B.Cu"
					(shape circle)
					(size 1.9939 1.9939)
					(thermal_gap 0.10795)
					(clearance 0.10795)
				)
			)
		)
		(pad "3" thru_hole circle
			(at -2.54 2.54 90)
			(size 1.9939 1.9939)
			(drill 0.249936)
			(layers "*.Cu" "*.Mask")
			(remove_unused_layers no)
			(net "T1_GND")
			(clearance 0.10795)
			(padstack
				(mode front_inner_back)
				(layer "Inner"
					(shape circle)
					(size 0.8001 0.8001)
					(clearance 0.1524)
				)
				(layer "B.Cu"
					(shape circle)
					(size 1.9939 1.9939)
					(thermal_gap 0.10795)
					(clearance 0.10795)
				)
			)
		)
		(pad "4" thru_hole circle
			(at 0 2.54 90)
			(size 1.0033 1.0033)
			(drill 0.249936)
			(layers "*.Cu" "*.Mask")
			(remove_unused_layers no)
			(net "TDR_DIFF_80_IN4_DP")
			(clearance 0.10795)
			(padstack
				(mode front_inner_back)
				(layer "Inner"
					(shape circle)
					(size 0.8001 0.8001)
					(clearance 0.1524)
				)
				(layer "B.Cu"
					(shape circle)
					(size 1.0033 1.0033)
					(thermal_gap 0.10795)
					(clearance 0.10795)
				)
			)
		)
	)
	(footprint ""
		(layer "B.Cu")
		(at 115.70589 -258.795266 180)
		(property "Reference" "C2441"
			(at 0 0 0)
			(layer "B.SilkS")
			(hide yes)
			(effects
				(font
					(size 1.27 1.27)
				)
				(justify mirror)
			)
		)
		(property "Value" ""
			(at 0 0 0)
			(layer "B.Fab")
			(effects
				(font
					(size 1.27 1.27)
				)
				(justify mirror)
			)
		)
		(duplicate_pad_numbers_are_jumpers no)
		(fp_line
			(start 0.7874 0.4064)
			(end 0.7874 -0.4064)
			(stroke
				(width 0.1524)
				(type default)
			)
			(layer "B.SilkS")
		)
		(fp_line
			(start 0.7874 -0.4064)
			(end -0.7874 -0.4064)
			(stroke
				(width 0.1524)
				(type default)
			)
			(layer "B.SilkS")
		)
		(fp_line
			(start -0.7874 0.4064)
			(end 0.7874 0.4064)
			(stroke
				(width 0.1524)
				(type default)
			)
			(layer "B.SilkS")
		)
		(fp_line
			(start -0.7874 -0.4064)
			(end -0.7874 0.4064)
			(stroke
				(width 0.1524)
				(type default)
			)
			(layer "B.SilkS")
		)
		(fp_line
			(start 0.67945 0.3048)
			(end 0.67945 -0.305054)
			(stroke
				(width 0.1)
				(type default)
			)
			(layer "B.Fab")
		)
		(fp_line
			(start 0.67945 -0.305054)
			(end 0.12065 -0.305054)
			(stroke
				(width 0.1)
				(type default)
			)
			(layer "B.Fab")
		)
		(fp_line
			(start 0.12065 0.3048)
			(end 0.67945 0.3048)
			(stroke
				(width 0.1)
				(type default)
			)
			(layer "B.Fab")
		)
		(fp_line
			(start 0.12065 0.2794)
			(end 0.12065 0.3048)
			(stroke
				(width 0.1)
				(type default)
			)
			(layer "B.Fab")
		)
		(fp_line
			(start 0.12065 -0.2794)
			(end -0.12065 -0.2794)
			(stroke
				(width 0.1)
				(type default)
			)
			(layer "B.Fab")
		)
		(fp_line
			(start 0.12065 -0.305054)
			(end 0.12065 -0.2794)
			(stroke
				(width 0.1)
				(type default)
			)
			(layer "B.Fab")
		)
		(fp_line
			(start -0.120396 0.3048)
			(end -0.120396 0.2794)
			(stroke
				(width 0.1)
				(type default)
			)
			(layer "B.Fab")
		)
		(fp_line
			(start -0.120396 0.2794)
			(end 0.12065 0.2794)
			(stroke
				(width 0.1)
				(type default)
			)
			(layer "B.Fab")
		)
		(fp_line
			(start -0.12065 -0.2794)
			(end -0.12065 -0.3048)
			(stroke
				(width 0.1)
				(type default)
			)
			(layer "B.Fab")
		)
		(fp_line
			(start -0.12065 -0.3048)
			(end -0.67945 -0.3048)
			(stroke
				(width 0.1)
				(type default)
			)
			(layer "B.Fab")
		)
		(fp_line
			(start -0.67945 0.3048)
			(end -0.120396 0.3048)
			(stroke
				(width 0.1)
				(type default)
			)
			(layer "B.Fab")
		)
		(fp_line
			(start -0.67945 -0.3048)
			(end -0.67945 0.3048)
			(stroke
				(width 0.1)
				(type default)
			)
			(layer "B.Fab")
		)
		(pad "1" smd circle
			(at 0.40005 0)
			(size 0 0)
			(layers "B.Cu" "B.Mask" "B.Paste")
			(net "PVDDCR_SOC_P1")
		)
		(pad "2" smd circle
			(at -0.40005 0)
			(size 0 0)
			(layers "B.Cu" "B.Mask" "B.Paste")
			(net "GND")
		)
	)
	(footprint ""
		(layer "B.Cu")
		(at 187.96 -418.846 90)
		(property "Reference" "U8005"
			(at -2.277364 2.563622 270)
			(unlocked yes)
			(layer "B.SilkS")
			(effects
				(font
					(size 0.7874 0.5842)
					(thickness 0.1524)
				)
				(justify left mirror)
			)
		)
		(property "Value" ""
			(at 0 0 90)
			(layer "B.Fab")
			(effects
				(font
					(size 1.27 1.27)
				)
				(justify mirror)
			)
		)
		(duplicate_pad_numbers_are_jumpers no)
		(fp_line
			(start 1.868424 -1.519936)
			(end 1.868424 1.519936)
			(stroke
				(width 0.1524)
				(type default)
			)
			(layer "B.SilkS")
		)
		(fp_line
			(start -1.868424 -1.519936)
			(end 1.868424 -1.519936)
			(stroke
				(width 0.1524)
				(type default)
			)
			(layer "B.SilkS")
		)
		(fp_line
			(start 1.868424 1.519936)
			(end -1.868424 1.519936)
			(stroke
				(width 0.1524)
				(type default)
			)
			(layer "B.SilkS")
		)
		(fp_line
			(start -1.868424 1.519936)
			(end -1.868424 -1.519936)
			(stroke
				(width 0.1524)
				(type default)
			)
			(layer "B.SilkS")
		)
		(fp_line
			(start 0.700024 -1.519936)
			(end 0.700024 1.519936)
			(stroke
				(width 0.1)
				(type default)
			)
			(layer "B.Fab")
		)
		(fp_line
			(start -0.700024 -1.519936)
			(end 0.700024 -1.519936)
			(stroke
				(width 0.1)
				(type default)
			)
			(layer "B.Fab")
		)
		(fp_line
			(start 0.700024 1.519936)
			(end -0.700024 1.519936)
			(stroke
				(width 0.1)
				(type default)
			)
			(layer "B.Fab")
		)
		(fp_line
			(start -0.700024 1.519936)
			(end -0.700024 -1.519936)
			(stroke
				(width 0.1)
				(type default)
			)
			(layer "B.Fab")
		)
		(pad "1" smd rect
			(at 1.18491 -0.94996)
			(size 0.6096 1.0668)
			(layers "B.Cu" "B.Mask" "B.Paste")
			(net "OC_P2V5_COMP")
		)
		(pad "2" smd rect
			(at 1.18491 0.94996)
			(size 0.6096 1.0668)
			(layers "B.Cu" "B.Mask" "B.Paste")
			(net "GND")
		)
		(pad "3" smd rect
			(at -1.18491 0)
			(size 0.6096 1.0668)
			(layers "B.Cu" "B.Mask" "B.Paste")
			(net "Net_10848")
		)
	)
	(footprint ""
		(layer "B.Cu")
		(at 121.8184 -388.011162 -90)
		(property "Reference" "C440"
			(at 0 0 90)
			(layer "B.SilkS")
			(hide yes)
			(effects
				(font
					(size 1.27 1.27)
				)
				(justify mirror)
			)
		)
		(property "Value" ""
			(at 0 0 90)
			(layer "B.Fab")
			(effects
				(font
					(size 1.27 1.27)
				)
				(justify mirror)
			)
		)
		(duplicate_pad_numbers_are_jumpers no)
		(fp_line
			(start -0.299974 0.150114)
			(end 0.299974 0.150114)
			(stroke
				(width 0.1)
				(type default)
			)
			(layer "B.Fab")
		)
		(fp_line
			(start 0.299974 0.150114)
			(end 0.299974 -0.150114)
			(stroke
				(width 0.1)
				(type default)
			)
			(layer "B.Fab")
		)
		(fp_line
			(start -0.299974 -0.150114)
			(end -0.299974 0.150114)
			(stroke
				(width 0.1)
				(type default)
			)
			(layer "B.Fab")
		)
		(fp_line
			(start 0.299974 -0.150114)
			(end -0.299974 -0.150114)
			(stroke
				(width 0.1)
				(type default)
			)
			(layer "B.Fab")
		)
		(pad "1" smd rect
			(at 0.2667 0 90)
			(size 0.3048 0.381)
			(layers "B.Cu" "B.Mask" "B.Paste")
			(net "P1V8_CPU1_RT3_1A")
		)
		(pad "2" smd rect
			(at -0.2667 0 90)
			(size 0.3048 0.381)
			(layers "B.Cu" "B.Mask" "B.Paste")
			(net "GND")
		)
	)
	(footprint ""
		(layer "B.Cu")
		(at 125.291342 -390.560052 90)
		(property "Reference" "C478"
			(at 0 0 90)
			(layer "B.SilkS")
			(hide yes)
			(effects
				(font
					(size 1.27 1.27)
				)
				(justify mirror)
			)
		)
		(property "Value" ""
			(at 0 0 90)
			(layer "B.Fab")
			(effects
				(font
					(size 1.27 1.27)
				)
				(justify mirror)
			)
		)
		(duplicate_pad_numbers_are_jumpers no)
		(fp_line
			(start 0.7874 -0.4064)
			(end -0.7874 -0.4064)
			(stroke
				(width 0.1524)
				(type default)
			)
			(layer "B.SilkS")
		)
		(fp_line
			(start -0.7874 -0.4064)
			(end -0.7874 0.4064)
			(stroke
				(width 0.1524)
				(type default)
			)
			(layer "B.SilkS")
		)
		(fp_line
			(start 0.7874 0.4064)
			(end 0.7874 -0.4064)
			(stroke
				(width 0.1524)
				(type default)
			)
			(layer "B.SilkS")
		)
		(fp_line
			(start -0.7874 0.4064)
			(end 0.7874 0.4064)
			(stroke
				(width 0.1524)
				(type default)
			)
			(layer "B.SilkS")
		)
		(fp_line
			(start 0.67945 -0.305054)
			(end 0.12065 -0.305054)
			(stroke
				(width 0.1)
				(type default)
			)
			(layer "B.Fab")
		)
		(fp_line
			(start 0.12065 -0.305054)
			(end 0.12065 -0.2794)
			(stroke
				(width 0.1)
				(type default)
			)
			(layer "B.Fab")
		)
		(fp_line
			(start -0.12065 -0.3048)
			(end -0.67945 -0.3048)
			(stroke
				(width 0.1)
				(type default)
			)
			(layer "B.Fab")
		)
		(fp_line
			(start -0.67945 -0.3048)
			(end -0.67945 0.3048)
			(stroke
				(width 0.1)
				(type default)
			)
			(layer "B.Fab")
		)
		(fp_line
			(start 0.12065 -0.2794)
			(end -0.12065 -0.2794)
			(stroke
				(width 0.1)
				(type default)
			)
			(layer "B.Fab")
		)
		(fp_line
			(start -0.12065 -0.2794)
			(end -0.12065 -0.3048)
			(stroke
				(width 0.1)
				(type default)
			)
			(layer "B.Fab")
		)
		(fp_line
			(start 0.12065 0.2794)
			(end 0.12065 0.3048)
			(stroke
				(width 0.1)
				(type default)
			)
			(layer "B.Fab")
		)
		(fp_line
			(start -0.120396 0.2794)
			(end 0.12065 0.2794)
			(stroke
				(width 0.1)
				(type default)
			)
			(layer "B.Fab")
		)
		(fp_line
			(start 0.67945 0.3048)
			(end 0.67945 -0.305054)
			(stroke
				(width 0.1)
				(type default)
			)
			(layer "B.Fab")
		)
		(fp_line
			(start 0.12065 0.3048)
			(end 0.67945 0.3048)
			(stroke
				(width 0.1)
				(type default)
			)
			(layer "B.Fab")
		)
		(fp_line
			(start -0.120396 0.3048)
			(end -0.120396 0.2794)
			(stroke
				(width 0.1)
				(type default)
			)
			(layer "B.Fab")
		)
		(fp_line
			(start -0.67945 0.3048)
			(end -0.120396 0.3048)
			(stroke
				(width 0.1)
				(type default)
			)
			(layer "B.Fab")
		)
		(pad "1" smd circle
			(at 0.40005 0 270)
			(size 0 0)
			(layers "B.Cu" "B.Mask" "B.Paste")
			(net "P0V9_CPU1_RT_2D")
		)
		(pad "2" smd circle
			(at -0.40005 0 270)
			(size 0 0)
			(layers "B.Cu" "B.Mask" "B.Paste")
			(net "GND")
		)
	)
	(footprint ""
		(layer "B.Cu")
		(at 65.3796 -15.8496)
		(property "Reference" "C1834"
			(at 0 0 0)
			(layer "B.SilkS")
			(hide yes)
			(effects
				(font
					(size 1.27 1.27)
				)
				(justify mirror)
			)
		)
		(property "Value" ""
			(at 0 0 0)
			(layer "B.Fab")
			(effects
				(font
					(size 1.27 1.27)
				)
				(justify mirror)
			)
		)
		(duplicate_pad_numbers_are_jumpers no)
		(fp_line
			(start -0.7874 -0.4064)
			(end -0.7874 0.4064)
			(stroke
				(width 0.1524)
				(type default)
			)
			(layer "B.SilkS")
		)
		(fp_line
			(start -0.7874 0.4064)
			(end 0.7874 0.4064)
			(stroke
				(width 0.1524)
				(type default)
			)
			(layer "B.SilkS")
		)
		(fp_line
			(start 0.7874 -0.4064)
			(end -0.7874 -0.4064)
			(stroke
				(width 0.1524)
				(type default)
			)
			(layer "B.SilkS")
		)
		(fp_line
			(start 0.7874 0.4064)
			(end 0.7874 -0.4064)
			(stroke
				(width 0.1524)
				(type default)
			)
			(layer "B.SilkS")
		)
		(fp_line
			(start -0.67945 -0.3048)
			(end -0.67945 0.3048)
			(stroke
				(width 0.1)
				(type default)
			)
			(layer "B.Fab")
		)
		(fp_line
			(start -0.67945 0.3048)
			(end -0.120396 0.3048)
			(stroke
				(width 0.1)
				(type default)
			)
			(layer "B.Fab")
		)
		(fp_line
			(start -0.12065 -0.3048)
			(end -0.67945 -0.3048)
			(stroke
				(width 0.1)
				(type default)
			)
			(layer "B.Fab")
		)
		(fp_line
			(start -0.12065 -0.2794)
			(end -0.12065 -0.3048)
			(stroke
				(width 0.1)
				(type default)
			)
			(layer "B.Fab")
		)
		(fp_line
			(start -0.120396 0.2794)
			(end 0.12065 0.2794)
			(stroke
				(width 0.1)
				(type default)
			)
			(layer "B.Fab")
		)
		(fp_line
			(start -0.120396 0.3048)
			(end -0.120396 0.2794)
			(stroke
				(width 0.1)
				(type default)
			)
			(layer "B.Fab")
		)
		(fp_line
			(start 0.12065 -0.305054)
			(end 0.12065 -0.2794)
			(stroke
				(width 0.1)
				(type default)
			)
			(layer "B.Fab")
		)
		(fp_line
			(start 0.12065 -0.2794)
			(end -0.12065 -0.2794)
			(stroke
				(width 0.1)
				(type default)
			)
			(layer "B.Fab")
		)
		(fp_line
			(start 0.12065 0.2794)
			(end 0.12065 0.3048)
			(stroke
				(width 0.1)
				(type default)
			)
			(layer "B.Fab")
		)
		(fp_line
			(start 0.12065 0.3048)
			(end 0.67945 0.3048)
			(stroke
				(width 0.1)
				(type default)
			)
			(layer "B.Fab")
		)
		(fp_line
			(start 0.67945 -0.305054)
			(end 0.12065 -0.305054)
			(stroke
				(width 0.1)
				(type default)
			)
			(layer "B.Fab")
		)
		(fp_line
			(start 0.67945 0.3048)
			(end 0.67945 -0.305054)
			(stroke
				(width 0.1)
				(type default)
			)
			(layer "B.Fab")
		)
		(pad "1" smd circle
			(at 0.40005 0 180)
			(size 0 0)
			(layers "B.Cu" "B.Mask" "B.Paste")
			(net "P12V_OCP_V3_2_R")
		)
		(pad "2" smd circle
			(at -0.40005 0 180)
			(size 0 0)
			(layers "B.Cu" "B.Mask" "B.Paste")
			(net "GND")
		)
	)
)
